(kicad_pcb
	(version 20260206)
	(generator "pcbnew")
	(generator_version "10.0")
	(general
		(thickness 1.6)
		(legacy_teardrops no)
	)
	(paper "A4")
	(title_block
		(title "v2-pdb — ms_pdb_v2.brd")
		(comment 1 "Open CloudServer (Microsoft) / footprints 294-302 of 348")
	)
	(layers
		(0 "F.Cu" signal "TOP")
		(4 "In1.Cu" signal "GND")
		(6 "In2.Cu" signal "IN1")
		(8 "In3.Cu" signal "VCC")
		(10 "In4.Cu" signal "VCC1")
		(12 "In5.Cu" signal "IN2")
		(14 "In6.Cu" signal "GND1")
		(2 "B.Cu" signal "BOTTOM")
		(9 "F.Adhes" user "F.Adhesive")
		(11 "B.Adhes" user "B.Adhesive")
		(13 "F.Paste" user "Package Geometry/Pastemask Top")
		(15 "B.Paste" user "Package Geometry/Pastemask Bottom")
		(5 "F.SilkS" user "Ref Des/Silkscreen Top")
		(7 "B.SilkS" user "Ref Des/Silkscreen Bottom")
		(1 "F.Mask" user "Board Geometry/Soldermask Top")
		(3 "B.Mask" user "Board Geometry/Soldermask Bottom")
		(17 "Dwgs.User" user "User.Drawings")
		(19 "Cmts.User" user "User.Comments")
		(21 "Eco1.User" user "User.Eco1")
		(23 "Eco2.User" user "User.Eco2")
		(25 "Edge.Cuts" user "Board Geometry/Outline")
		(27 "Margin" user)
		(31 "F.CrtYd" user "Package Geometry/Place Bound Top")
		(29 "B.CrtYd" user "Package Geometry/Place Bound Bottom")
		(35 "F.Fab" user "Ref Des/Assembly Top")
		(33 "B.Fab" user "Ref Des/Assembly Bottom")
	)
	(footprint ""
		(layer "F.Cu")
		(at 27.28468 -5.10032)
		(property "Reference" "R45"
			(at -1.676146 2.569972 0)
			(unlocked yes)
			(layer "F.SilkS")
			(effects
				(font
					(size 0.7874 0.5842)
					(thickness 0.1524)
				)
				(justify left)
			)
		)
		(property "Value" ""
			(at 0 0 0)
			(layer "F.Fab")
			(effects
				(font
					(size 1.27 1.27)
				)
			)
		)
		(duplicate_pad_numbers_are_jumpers no)
		(fp_line
			(start -0.7874 -0.4064)
			(end 0.7874 -0.4064)
			(stroke
				(width 0.1524)
				(type default)
			)
			(layer "F.SilkS")
		)
		(fp_line
			(start -0.7874 0.4064)
			(end -0.7874 -0.4064)
			(stroke
				(width 0.1524)
				(type default)
			)
			(layer "F.SilkS")
		)
		(fp_line
			(start 0.7874 -0.4064)
			(end 0.7874 0.4064)
			(stroke
				(width 0.1524)
				(type default)
			)
			(layer "F.SilkS")
		)
		(fp_line
			(start 0.7874 0.4064)
			(end -0.7874 0.4064)
			(stroke
				(width 0.1524)
				(type default)
			)
			(layer "F.SilkS")
		)
		(fp_poly
			(pts
				(xy -0.508 0.2794) (xy -0.508 0.2286) (xy -0.635 0.2286) (xy -0.635 -0.254) (xy -0.5334 -0.254)
				(xy -0.5334 -0.2794) (xy 0.5334 -0.2794) (xy 0.5334 -0.254) (xy 0.635 -0.254) (xy 0.635 0.254) (xy 0.5334 0.254)
				(xy 0.5334 0.2794)
			)
			(stroke
				(width 0)
				(type default)
			)
			(fill no)
			(layer "F.CrtYd")
		)
		(pad "1" smd rect
			(at 0.40005 0)
			(size 0.4572 0.508)
			(layers "F.Cu" "F.Mask" "F.Paste")
			(net "PSU1_RESET")
		)
		(pad "2" smd rect
			(at -0.40005 0)
			(size 0.4572 0.508)
			(layers "F.Cu" "F.Mask" "F.Paste")
			(net "GND")
		)
	)
	(footprint ""
		(layer "F.Cu")
		(at 51.613054 -240.589308 180)
		(property "Reference" "CE12"
			(at -5.020056 0.183388 0)
			(unlocked yes)
			(layer "F.SilkS")
			(effects
				(font
					(size 0.7874 0.5842)
					(thickness 0.1524)
				)
				(justify left)
			)
		)
		(property "Value" ""
			(at 0 0 180)
			(layer "F.Fab")
			(effects
				(font
					(size 1.27 1.27)
				)
			)
		)
		(duplicate_pad_numbers_are_jumpers no)
		(fp_line
			(start 0 -4.2672)
			(end 0 4.2672)
			(stroke
				(width 0.1524)
				(type default)
			)
			(layer "F.SilkS")
		)
		(fp_circle
			(center 0 0)
			(end -4.2672 0)
			(stroke
				(width 0.1524)
				(type default)
			)
			(fill no)
			(layer "F.SilkS")
		)
		(fp_poly
			(pts
				(arc
					(start 0 -4.2672)
					(mid 4.2672 0)
					(end 0 4.2672)
				)
			)
			(stroke
				(width 0)
				(type default)
			)
			(fill yes)
			(layer "F.SilkS")
		)
		(fp_poly
			(pts
				(xy -2.5146 -0.762) (xy -0.9906 -0.762) (xy -0.9906 0.762) (xy -2.5146 0.762)
			)
			(stroke
				(width 0)
				(type default)
			)
			(fill no)
			(layer "B.CrtYd")
		)
		(fp_poly
			(pts
				(arc
					(start 1.7526 0.762)
					(mid 2.291415 -0.538815)
					(end 0.9906 0)
				)
				(arc
					(start 0.9906 0.0254)
					(mid 1.206345 0.546255)
					(end 1.7272 0.762)
				)
			)
			(stroke
				(width 0)
				(type default)
			)
			(fill no)
			(layer "B.CrtYd")
		)
		(fp_poly
			(pts
				(arc
					(start -4.2672 0)
					(mid 4.2672 0)
					(end -4.2672 0)
				)
			)
			(stroke
				(width 0)
				(type default)
			)
			(fill no)
			(layer "F.CrtYd")
		)
		(fp_circle
			(center 0 0)
			(end -4.2672 0)
			(stroke
				(width 0.1)
				(type default)
			)
			(fill no)
			(layer "F.Fab")
		)
		(fp_text user "+"
			(at -6.029198 -1.809242 180)
			(unlocked yes)
			(layer "F.SilkS")
			(effects
				(font
					(size 1.905 1.4224)
					(thickness 0.1524)
				)
				(justify left)
			)
		)
		(fp_text user "+"
			(at -5.6642 -0.34925 180)
			(unlocked yes)
			(layer "F.Fab")
			(effects
				(font
					(size 1.905 1.4224)
					(thickness 0.000001)
				)
				(justify left)
			)
		)
		(pad "1" thru_hole rect
			(at -1.75006 0 180)
			(size 1.397 1.397)
			(drill 0.9144)
			(layers "*.Cu" "*.Mask")
			(remove_unused_layers no)
			(net "P12V")
			(clearance 0.0127)
			(thermal_gap 0.0127)
			(padstack
				(mode front_inner_back)
				(layer "Inner"
					(shape circle)
					(size 1.397 1.397)
					(clearance 0.0127)
				)
				(layer "B.Cu"
					(shape rect)
					(size 1.397 1.397)
					(clearance 0.0127)
				)
			)
		)
		(pad "2" thru_hole circle
			(at 1.75006 0 180)
			(size 1.397 1.397)
			(drill 0.9144)
			(layers "*.Cu" "*.Mask")
			(remove_unused_layers no)
			(net "GND")
			(clearance 0.0127)
			(thermal_gap 0.0127)
		)
	)
	(footprint ""
		(layer "F.Cu")
		(at 78.397354 -18.749772 -90)
		(property "Reference" "C4"
			(at -1.75133 0.035052 90)
			(unlocked yes)
			(layer "F.SilkS")
			(effects
				(font
					(size 0.7874 0.5842)
					(thickness 0.1524)
				)
				(justify left)
			)
		)
		(property "Value" ""
			(at 0 0 270)
			(layer "F.Fab")
			(effects
				(font
					(size 1.27 1.27)
				)
			)
		)
		(duplicate_pad_numbers_are_jumpers no)
		(fp_line
			(start -0.7874 0.4064)
			(end -0.7874 -0.4064)
			(stroke
				(width 0.1524)
				(type default)
			)
			(layer "F.SilkS")
		)
		(fp_line
			(start 0.7874 0.4064)
			(end -0.7874 0.4064)
			(stroke
				(width 0.1524)
				(type default)
			)
			(layer "F.SilkS")
		)
		(fp_line
			(start 0 0.381)
			(end 0 -0.381)
			(stroke
				(width 0.1524)
				(type default)
			)
			(layer "F.SilkS")
		)
		(fp_line
			(start -0.7874 -0.4064)
			(end 0.7874 -0.4064)
			(stroke
				(width 0.1524)
				(type default)
			)
			(layer "F.SilkS")
		)
		(fp_line
			(start 0.7874 -0.4064)
			(end 0.7874 0.4064)
			(stroke
				(width 0.1524)
				(type default)
			)
			(layer "F.SilkS")
		)
		(fp_poly
			(pts
				(xy -0.5334 0.254) (xy -0.635 0.254) (xy -0.635 0.2286) (xy -0.635 -0.254) (xy -0.5334 -0.254) (xy -0.5334 -0.2794)
				(xy 0.5334 -0.2794) (xy 0.5334 -0.254) (xy 0.635 -0.254) (xy 0.635 0.254) (xy 0.5334 0.254) (xy 0.5334 0.2794)
				(xy -0.508 0.2794) (xy -0.5334 0.2794)
			)
			(stroke
				(width 0)
				(type default)
			)
			(fill no)
			(layer "F.CrtYd")
		)
		(pad "1" smd rect
			(at 0.40005 0 270)
			(size 0.4572 0.508)
			(layers "F.Cu" "F.Mask" "F.Paste")
			(net "P12V")
		)
		(pad "2" smd rect
			(at -0.40005 0 270)
			(size 0.4572 0.508)
			(layers "F.Cu" "F.Mask" "F.Paste")
			(net "GND")
		)
	)
	(footprint ""
		(layer "F.Cu")
		(at 91.399868 -464.509866)
		(property "Reference" "H19"
			(at -5.1308 -5.23113 0)
			(unlocked yes)
			(layer "F.SilkS")
			(effects
				(font
					(size 0.7874 0.5842)
					(thickness 0.1524)
				)
				(justify left)
			)
		)
		(property "Value" ""
			(at 0 0 0)
			(layer "F.Fab")
			(effects
				(font
					(size 1.27 1.27)
				)
			)
		)
		(duplicate_pad_numbers_are_jumpers no)
		(fp_circle
			(center 0 0)
			(end 4.826 0)
			(stroke
				(width 0.1524)
				(type default)
			)
			(fill no)
			(layer "F.SilkS")
		)
		(fp_circle
			(center 0 0)
			(end 4.826 0)
			(stroke
				(width 0.1524)
				(type default)
			)
			(fill no)
			(layer "B.SilkS")
		)
		(fp_poly
			(pts
				(arc
					(start 0 4.0132)
					(mid 0 -4.0132)
					(end 0 4.0132)
				)
			)
			(stroke
				(width 0)
				(type default)
			)
			(fill no)
			(layer "F.CrtYd")
		)
		(pad "" np_thru_hole circle
			(at 0 0)
			(size 8.001 8.001)
			(drill 8.001)
			(layers "*.Cu" "*.Mask")
			(clearance 0.381)
			(thermal_gap 0.381)
		)
		(zone
			(layers "F.Cu" "B.Cu" "In1.Cu" "In2.Cu" "In3.Cu" "In4.Cu" "In5.Cu" "In6.Cu")
			(hatch none 0.5)
			(connect_pads
				(clearance 0)
			)
			(min_thickness 0.25)
			(keepout
				(tracks not_allowed)
				(vias allowed)
				(pads allowed)
				(copperpour not_allowed)
				(footprints allowed)
			)
			(placement
				(enabled no)
				(sheetname "")
			)
			(fill
				(thermal_gap 0.5)
				(thermal_bridge_width 0.5)
				(island_removal_mode 0)
			)
			(polygon
				(pts
					(arc
						(start 91.399868 -459.988666)
						(mid 91.399868 -469.031066)
						(end 91.399868 -459.988666)
					)
				)
			)
		)
	)
	(footprint ""
		(layer "F.Cu")
		(at 79.898748 -508.382778 -90)
		(property "Reference" "C78"
			(at 2.76606 -0.024892 90)
			(unlocked yes)
			(layer "F.SilkS")
			(effects
				(font
					(size 0.7874 0.5842)
					(thickness 0.1524)
				)
			)
		)
		(property "Value" ""
			(at 0 0 270)
			(layer "F.Fab")
			(effects
				(font
					(size 1.27 1.27)
				)
			)
		)
		(duplicate_pad_numbers_are_jumpers no)
		(fp_line
			(start -1.2954 0.5842)
			(end -1.2954 -0.5842)
			(stroke
				(width 0.1524)
				(type default)
			)
			(layer "F.SilkS")
		)
		(fp_line
			(start 1.2954 0.5842)
			(end -1.2954 0.5842)
			(stroke
				(width 0.1524)
				(type default)
			)
			(layer "F.SilkS")
		)
		(fp_line
			(start -1.2954 -0.5842)
			(end 1.2954 -0.5842)
			(stroke
				(width 0.1524)
				(type default)
			)
			(layer "F.SilkS")
		)
		(fp_line
			(start 0 -0.5842)
			(end 0 0.5842)
			(stroke
				(width 0.1524)
				(type default)
			)
			(layer "F.SilkS")
		)
		(fp_line
			(start 1.2954 -0.5842)
			(end 1.2954 0.5842)
			(stroke
				(width 0.1524)
				(type default)
			)
			(layer "F.SilkS")
		)
		(fp_poly
			(pts
				(xy 0.8636 -0.4572) (xy 0.8636 -0.3556) (xy 1.143 -0.3556) (xy 1.143 0.3556) (xy 0.8636 0.3556)
				(xy 0.8636 0.4572) (xy -0.8636 0.4572) (xy -0.8636 0.3556) (xy -1.143 0.3556) (xy -1.143 -0.3556)
				(xy -0.8636 -0.3556) (xy -0.8636 -0.4572)
			)
			(stroke
				(width 0)
				(type default)
			)
			(fill no)
			(layer "F.CrtYd")
		)
		(fp_line
			(start -0.884936 0.504952)
			(end -0.884936 -0.504952)
			(stroke
				(width 0.1)
				(type default)
			)
			(layer "F.Fab")
		)
		(fp_line
			(start 0.884936 0.504952)
			(end -0.884936 0.504952)
			(stroke
				(width 0.1)
				(type default)
			)
			(layer "F.Fab")
		)
		(fp_line
			(start -0.884936 -0.504952)
			(end 0.884936 -0.504952)
			(stroke
				(width 0.1)
				(type default)
			)
			(layer "F.Fab")
		)
		(fp_line
			(start 0.884936 -0.504952)
			(end 0.884936 0.504952)
			(stroke
				(width 0.1)
				(type default)
			)
			(layer "F.Fab")
		)
		(pad "1" smd rect
			(at 0.7366 0)
			(size 0.7112 0.8128)
			(layers "F.Cu" "F.Mask" "F.Paste")
			(net "P12V")
		)
		(pad "2" smd rect
			(at -0.7366 0)
			(size 0.7112 0.8128)
			(layers "F.Cu" "F.Mask" "F.Paste")
			(net "GND")
		)
	)
	(footprint ""
		(layer "F.Cu")
		(at 77.999844 -78.299818)
		(property "Reference" "H14"
			(at -1.764792 -4.65709 0)
			(unlocked yes)
			(layer "F.SilkS")
			(effects
				(font
					(size 0.7874 0.5842)
					(thickness 0.1524)
				)
				(justify left)
			)
		)
		(property "Value" ""
			(at 0 0 0)
			(layer "F.Fab")
			(effects
				(font
					(size 1.27 1.27)
				)
			)
		)
		(duplicate_pad_numbers_are_jumpers no)
		(fp_circle
			(center 0 0)
			(end 3.4163 0)
			(stroke
				(width 0.1524)
				(type default)
			)
			(fill no)
			(layer "F.SilkS")
		)
		(fp_circle
			(center 0 0)
			(end 3.41884 0)
			(stroke
				(width 0.1524)
				(type default)
			)
			(fill no)
			(layer "B.SilkS")
		)
		(fp_poly
			(pts
				(arc
					(start 2.8575 0)
					(mid -2.8575 0)
					(end 2.8575 0)
				)
			)
			(stroke
				(width 0)
				(type default)
			)
			(fill no)
			(layer "B.CrtYd")
		)
		(fp_poly
			(pts
				(arc
					(start 2.8575 0)
					(mid -2.8575 0)
					(end 2.8575 0)
				)
			)
			(stroke
				(width 0)
				(type default)
			)
			(fill no)
			(layer "F.CrtYd")
		)
		(pad "" np_thru_hole circle
			(at 0 0)
			(size 5.207 5.207)
			(drill 5.207)
			(layers "*.Cu" "*.Mask")
			(clearance 0.381)
			(thermal_gap 0.381)
		)
		(zone
			(layers "F.Cu" "B.Cu" "In1.Cu" "In2.Cu" "In3.Cu" "In4.Cu" "In5.Cu" "In6.Cu")
			(hatch none 0.5)
			(connect_pads
				(clearance 0)
			)
			(min_thickness 0.25)
			(keepout
				(tracks not_allowed)
				(vias allowed)
				(pads allowed)
				(copperpour not_allowed)
				(footprints allowed)
			)
			(placement
				(enabled no)
				(sheetname "")
			)
			(fill
				(thermal_gap 0.5)
				(thermal_bridge_width 0.5)
				(island_removal_mode 0)
			)
			(polygon
				(pts
					(arc
						(start 81.111344 -78.299818)
						(mid 74.888344 -78.299818)
						(end 81.111344 -78.299818)
					)
				)
			)
		)
	)
	(footprint ""
		(layer "F.Cu")
		(at 77.43698 -393.452604 90)
		(property "Reference" "C67"
			(at 1.08458 0.350012 90)
			(unlocked yes)
			(layer "F.SilkS")
			(effects
				(font
					(size 0.7874 0.5842)
					(thickness 0.1524)
				)
				(justify left)
			)
		)
		(property "Value" ""
			(at 0 0 90)
			(layer "F.Fab")
			(effects
				(font
					(size 1.27 1.27)
				)
			)
		)
		(duplicate_pad_numbers_are_jumpers no)
		(fp_line
			(start 0.7874 -0.4064)
			(end 0.7874 0.4064)
			(stroke
				(width 0.1524)
				(type default)
			)
			(layer "F.SilkS")
		)
		(fp_line
			(start -0.7874 -0.4064)
			(end 0.7874 -0.4064)
			(stroke
				(width 0.1524)
				(type default)
			)
			(layer "F.SilkS")
		)
		(fp_line
			(start 0 0.381)
			(end 0 -0.381)
			(stroke
				(width 0.1524)
				(type default)
			)
			(layer "F.SilkS")
		)
		(fp_line
			(start 0.7874 0.4064)
			(end -0.7874 0.4064)
			(stroke
				(width 0.1524)
				(type default)
			)
			(layer "F.SilkS")
		)
		(fp_line
			(start -0.7874 0.4064)
			(end -0.7874 -0.4064)
			(stroke
				(width 0.1524)
				(type default)
			)
			(layer "F.SilkS")
		)
		(fp_poly
			(pts
				(xy -0.5334 0.254) (xy -0.635 0.254) (xy -0.635 0.2286) (xy -0.635 -0.254) (xy -0.5334 -0.254) (xy -0.5334 -0.2794)
				(xy 0.5334 -0.2794) (xy 0.5334 -0.254) (xy 0.635 -0.254) (xy 0.635 0.254) (xy 0.5334 0.254) (xy 0.5334 0.2794)
				(xy -0.508 0.2794) (xy -0.5334 0.2794)
			)
			(stroke
				(width 0)
				(type default)
			)
			(fill no)
			(layer "F.CrtYd")
		)
		(pad "1" smd rect
			(at 0.40005 0 90)
			(size 0.4572 0.508)
			(layers "F.Cu" "F.Mask" "F.Paste")
			(net "P12V")
		)
		(pad "2" smd rect
			(at -0.40005 0 90)
			(size 0.4572 0.508)
			(layers "F.Cu" "F.Mask" "F.Paste")
			(net "GND")
		)
	)
	(footprint ""
		(layer "F.Cu")
		(at 21.511514 -449.860162 180)
		(property "Reference" "C91"
			(at -0.285496 -7.5057 0)
			(unlocked yes)
			(layer "F.SilkS")
			(effects
				(font
					(size 0.7874 0.5842)
					(thickness 0.1524)
				)
				(justify left)
			)
		)
		(property "Value" ""
			(at 0 0 180)
			(layer "F.Fab")
			(effects
				(font
					(size 1.27 1.27)
				)
			)
		)
		(duplicate_pad_numbers_are_jumpers no)
		(fp_line
			(start 0.7874 0.4064)
			(end -0.7874 0.4064)
			(stroke
				(width 0.1524)
				(type default)
			)
			(layer "F.SilkS")
		)
		(fp_line
			(start 0.7874 -0.4064)
			(end 0.7874 0.4064)
			(stroke
				(width 0.1524)
				(type default)
			)
			(layer "F.SilkS")
		)
		(fp_line
			(start 0 0.381)
			(end 0 -0.381)
			(stroke
				(width 0.1524)
				(type default)
			)
			(layer "F.SilkS")
		)
		(fp_line
			(start -0.7874 0.4064)
			(end -0.7874 -0.4064)
			(stroke
				(width 0.1524)
				(type default)
			)
			(layer "F.SilkS")
		)
		(fp_line
			(start -0.7874 -0.4064)
			(end 0.7874 -0.4064)
			(stroke
				(width 0.1524)
				(type default)
			)
			(layer "F.SilkS")
		)
		(fp_poly
			(pts
				(xy -0.5334 0.254) (xy -0.635 0.254) (xy -0.635 0.2286) (xy -0.635 -0.254) (xy -0.5334 -0.254) (xy -0.5334 -0.2794)
				(xy 0.5334 -0.2794) (xy 0.5334 -0.254) (xy 0.635 -0.254) (xy 0.635 0.254) (xy 0.5334 0.254) (xy 0.5334 0.2794)
				(xy -0.508 0.2794) (xy -0.5334 0.2794)
			)
			(stroke
				(width 0)
				(type default)
			)
			(fill no)
			(layer "F.CrtYd")
		)
		(pad "1" smd rect
			(at 0.40005 0 180)
			(size 0.4572 0.508)
			(layers "F.Cu" "F.Mask" "F.Paste")
			(net "P3V3_BUF")
		)
		(pad "2" smd rect
			(at -0.40005 0 180)
			(size 0.4572 0.508)
			(layers "F.Cu" "F.Mask" "F.Paste")
			(net "GND")
		)
	)
	(footprint ""
		(layer "F.Cu")
		(at 12.784074 -330.48067 -90)
		(property "Reference" "R36"
			(at 3.685032 -0.234188 90)
			(unlocked yes)
			(layer "F.SilkS")
			(effects
				(font
					(size 0.7874 0.5842)
					(thickness 0.1524)
				)
				(justify left)
			)
		)
		(property "Value" ""
			(at 0 0 270)
			(layer "F.Fab")
			(effects
				(font
					(size 1.27 1.27)
				)
			)
		)
		(duplicate_pad_numbers_are_jumpers no)
		(fp_line
			(start -0.7874 0.4064)
			(end -0.7874 -0.4064)
			(stroke
				(width 0.1524)
				(type default)
			)
			(layer "F.SilkS")
		)
		(fp_line
			(start 0.7874 0.4064)
			(end -0.7874 0.4064)
			(stroke
				(width 0.1524)
				(type default)
			)
			(layer "F.SilkS")
		)
		(fp_line
			(start -0.7874 -0.4064)
			(end 0.7874 -0.4064)
			(stroke
				(width 0.1524)
				(type default)
			)
			(layer "F.SilkS")
		)
		(fp_line
			(start 0.7874 -0.4064)
			(end 0.7874 0.4064)
			(stroke
				(width 0.1524)
				(type default)
			)
			(layer "F.SilkS")
		)
		(fp_poly
			(pts
				(xy -0.508 0.2794) (xy -0.508 0.2286) (xy -0.635 0.2286) (xy -0.635 -0.254) (xy -0.5334 -0.254)
				(xy -0.5334 -0.2794) (xy 0.5334 -0.2794) (xy 0.5334 -0.254) (xy 0.635 -0.254) (xy 0.635 0.254) (xy 0.5334 0.254)
				(xy 0.5334 0.2794)
			)
			(stroke
				(width 0)
				(type default)
			)
			(fill no)
			(layer "F.CrtYd")
		)
		(pad "1" smd rect
			(at 0.40005 0 270)
			(size 0.4572 0.508)
			(layers "F.Cu" "F.Mask" "F.Paste")
			(net "P3V3")
		)
		(pad "2" smd rect
			(at -0.40005 0 270)
			(size 0.4572 0.508)
			(layers "F.Cu" "F.Mask" "F.Paste")
			(net "FRU_A2")
		)
	)
)
